# T6G (Grand Teton) — schematic netlist excerpt (pin names and nets, part order shuffled) for the footprints in the layout excerpt that follows; sources: Cadence DE-HDL packaged netlist, KiCad conversion of 04192023_DAF0TMB3IC0_F0TG_MB_C_brd_V02_OCP.brd

C1283  Q_CAP  0.1UF 25V 10% X7R  pkg 0402  page 145 : A = P3V3_E1S_0 ; B = GND
PC127_4  Q_CAP  22UF 4V 20% X6S  pkg C0805  page 202 : A = PVDDCR_CPU1_P0 ; B = GND
C183  Q_CAP  10UF 25V 10% X6S  pkg C0805  page 102 : A = P12V_MEM_CPU1 ; B = GND

(kicad_pcb
	(version 20260206)
	(generator "pcbnew")
	(generator_version "10.0")
	(general
		(thickness 1.6)
		(legacy_teardrops no)
	)
	(paper "A4")
	(title_block
		(title "04192023_DAF0TMB3IC0_F0TG_MB_C_brd_V02_OCP.brd")
		(comment 1 "Grand Teton / footprints 6212-6214 of 8354")
	)
	(layers
		(0 "F.Cu" signal "TOP")
		(4 "In1.Cu" signal "GND")
		(6 "In2.Cu" signal "IN1")
		(8 "In3.Cu" signal "GND1")
		(10 "In4.Cu" signal "IN2")
		(12 "In5.Cu" signal "GND2")
		(14 "In6.Cu" signal "IN3")
		(16 "In7.Cu" signal "GND3")
		(18 "In8.Cu" signal "VCC")
		(20 "In9.Cu" signal "VCC1")
		(22 "In10.Cu" signal "GND4")
		(24 "In11.Cu" signal "IN4")
		(26 "In12.Cu" signal "GND5")
		(28 "In13.Cu" signal "IN5")
		(30 "In14.Cu" signal "GND6")
		(32 "In15.Cu" signal "IN6")
		(34 "In16.Cu" signal "GND7")
		(2 "B.Cu" signal "BOTTOM")
		(9 "F.Adhes" user "F.Adhesive")
		(11 "B.Adhes" user "B.Adhesive")
		(13 "F.Paste" user "Package Geometry/Pastemask Top")
		(15 "B.Paste" user "Package Geometry/Pastemask Bottom")
		(5 "F.SilkS" user "Ref Des/Silkscreen Top")
		(7 "B.SilkS" user "Ref Des/Silkscreen Bottom")
		(1 "F.Mask" user "Board Geometry/Soldermask Top")
		(3 "B.Mask" user "Board Geometry/Soldermask Bottom")
		(17 "Dwgs.User" user "User.Drawings")
		(19 "Cmts.User" user "User.Comments")
		(21 "Eco1.User" user "User.Eco1")
		(23 "Eco2.User" user "User.Eco2")
		(25 "Edge.Cuts" user "Board Geometry/Outline")
		(27 "Margin" user)
		(31 "F.CrtYd" user "Package Geometry/Place Bound Top")
		(29 "B.CrtYd" user "Package Geometry/Place Bound Bottom")
		(35 "F.Fab" user "Ref Des/Assembly Top")
		(33 "B.Fab" user "Ref Des/Assembly Bottom")
	)
	(footprint ""
		(layer "B.Cu")
		(at 29.252164 -192.66027)
		(property "Reference" "C183"
			(at 0 0 0)
			(layer "B.SilkS")
			(hide yes)
			(effects
				(font
					(size 1.27 1.27)
				)
				(justify mirror)
			)
		)
		(property "Value" ""
			(at 0 0 0)
			(layer "B.Fab")
			(effects
				(font
					(size 1.27 1.27)
				)
				(justify mirror)
			)
		)
		(duplicate_pad_numbers_are_jumpers no)
		(fp_line
			(start -1.524 -0.762)
			(end -1.524 0.762)
			(stroke
				(width 0.1524)
				(type default)
			)
			(layer "B.SilkS")
		)
		(fp_line
			(start -1.524 0.762)
			(end 1.524 0.762)
			(stroke
				(width 0.1524)
				(type default)
			)
			(layer "B.SilkS")
		)
		(fp_line
			(start 1.524 -0.762)
			(end -1.524 -0.762)
			(stroke
				(width 0.1524)
				(type default)
			)
			(layer "B.SilkS")
		)
		(fp_line
			(start 1.524 0.762)
			(end 1.524 -0.762)
			(stroke
				(width 0.1524)
				(type default)
			)
			(layer "B.SilkS")
		)
		(fp_line
			(start -1.1049 -0.724916)
			(end 1.1049 -0.724916)
			(stroke
				(width 0.1)
				(type default)
			)
			(layer "B.Fab")
		)
		(fp_line
			(start -1.1049 0.724916)
			(end -1.1049 -0.724916)
			(stroke
				(width 0.1)
				(type default)
			)
			(layer "B.Fab")
		)
		(fp_line
			(start 1.1049 -0.724916)
			(end 1.1049 0.724916)
			(stroke
				(width 0.1)
				(type default)
			)
			(layer "B.Fab")
		)
		(fp_line
			(start 1.1049 0.724916)
			(end -1.1049 0.724916)
			(stroke
				(width 0.1)
				(type default)
			)
			(layer "B.Fab")
		)
		(pad "1" smd rect
			(at 0.889 0)
			(size 1.016 1.27)
			(layers "B.Cu" "B.Mask" "B.Paste")
			(net "P12V_MEM_CPU1")
		)
		(pad "2" smd rect
			(at -0.889 0)
			(size 1.016 1.27)
			(layers "B.Cu" "B.Mask" "B.Paste")
			(net "GND")
		)
	)
	(footprint ""
		(layer "B.Cu")
		(at 305.239928 -338.082128 -90)
		(property "Reference" "PC127_4"
			(at 0 0 90)
			(layer "B.SilkS")
			(hide yes)
			(effects
				(font
					(size 1.27 1.27)
				)
				(justify mirror)
			)
		)
		(property "Value" ""
			(at 0 0 90)
			(layer "B.Fab")
			(effects
				(font
					(size 1.27 1.27)
				)
				(justify mirror)
			)
		)
		(duplicate_pad_numbers_are_jumpers no)
		(fp_line
			(start -1.524 0.762)
			(end 1.524 0.762)
			(stroke
				(width 0.1524)
				(type default)
			)
			(layer "B.SilkS")
		)
		(fp_line
			(start 1.524 0.762)
			(end 1.524 -0.762)
			(stroke
				(width 0.1524)
				(type default)
			)
			(layer "B.SilkS")
		)
		(fp_line
			(start -1.524 -0.762)
			(end -1.524 0.762)
			(stroke
				(width 0.1524)
				(type default)
			)
			(layer "B.SilkS")
		)
		(fp_line
			(start 1.524 -0.762)
			(end -1.524 -0.762)
			(stroke
				(width 0.1524)
				(type default)
			)
			(layer "B.SilkS")
		)
		(fp_line
			(start -1.1049 0.724916)
			(end -1.1049 -0.724916)
			(stroke
				(width 0.1)
				(type default)
			)
			(layer "B.Fab")
		)
		(fp_line
			(start 1.1049 0.724916)
			(end -1.1049 0.724916)
			(stroke
				(width 0.1)
				(type default)
			)
			(layer "B.Fab")
		)
		(fp_line
			(start -1.1049 -0.724916)
			(end 1.1049 -0.724916)
			(stroke
				(width 0.1)
				(type default)
			)
			(layer "B.Fab")
		)
		(fp_line
			(start 1.1049 -0.724916)
			(end 1.1049 0.724916)
			(stroke
				(width 0.1)
				(type default)
			)
			(layer "B.Fab")
		)
		(pad "1" smd rect
			(at 0.889 0 270)
			(size 1.016 1.27)
			(layers "B.Cu" "B.Mask" "B.Paste")
			(net "PVDDCR_CPU1_P0")
		)
		(pad "2" smd rect
			(at -0.889 0 270)
			(size 1.016 1.27)
			(layers "B.Cu" "B.Mask" "B.Paste")
			(net "GND")
		)
	)
	(footprint ""
		(layer "B.Cu")
		(at 236.62513 -48.104044)
		(property "Reference" "C1283"
			(at 0 0 0)
			(layer "B.SilkS")
			(hide yes)
			(effects
				(font
					(size 1.27 1.27)
				)
				(justify mirror)
			)
		)
		(property "Value" ""
			(at 0 0 0)
			(layer "B.Fab")
			(effects
				(font
					(size 1.27 1.27)
				)
				(justify mirror)
			)
		)
		(duplicate_pad_numbers_are_jumpers no)
		(fp_line
			(start -0.7874 -0.4064)
			(end -0.7874 0.4064)
			(stroke
				(width 0.1524)
				(type default)
			)
			(layer "B.SilkS")
		)
		(fp_line
			(start -0.7874 0.4064)
			(end 0.7874 0.4064)
			(stroke
				(width 0.1524)
				(type default)
			)
			(layer "B.SilkS")
		)
		(fp_line
			(start 0.7874 -0.4064)
			(end -0.7874 -0.4064)
			(stroke
				(width 0.1524)
				(type default)
			)
			(layer "B.SilkS")
		)
		(fp_line
			(start 0.7874 0.4064)
			(end 0.7874 -0.4064)
			(stroke
				(width 0.1524)
				(type default)
			)
			(layer "B.SilkS")
		)
		(fp_line
			(start -0.67945 -0.3048)
			(end -0.67945 0.3048)
			(stroke
				(width 0.1)
				(type default)
			)
			(layer "B.Fab")
		)
		(fp_line
			(start -0.67945 0.3048)
			(end -0.120396 0.3048)
			(stroke
				(width 0.1)
				(type default)
			)
			(layer "B.Fab")
		)
		(fp_line
			(start -0.12065 -0.3048)
			(end -0.67945 -0.3048)
			(stroke
				(width 0.1)
				(type default)
			)
			(layer "B.Fab")
		)
		(fp_line
			(start -0.12065 -0.2794)
			(end -0.12065 -0.3048)
			(stroke
				(width 0.1)
				(type default)
			)
			(layer "B.Fab")
		)
		(fp_line
			(start -0.120396 0.2794)
			(end 0.12065 0.2794)
			(stroke
				(width 0.1)
				(type default)
			)
			(layer "B.Fab")
		)
		(fp_line
			(start -0.120396 0.3048)
			(end -0.120396 0.2794)
			(stroke
				(width 0.1)
				(type default)
			)
			(layer "B.Fab")
		)
		(fp_line
			(start 0.12065 -0.305054)
			(end 0.12065 -0.2794)
			(stroke
				(width 0.1)
				(type default)
			)
			(layer "B.Fab")
		)
		(fp_line
			(start 0.12065 -0.2794)
			(end -0.12065 -0.2794)
			(stroke
				(width 0.1)
				(type default)
			)
			(layer "B.Fab")
		)
		(fp_line
			(start 0.12065 0.2794)
			(end 0.12065 0.3048)
			(stroke
				(width 0.1)
				(type default)
			)
			(layer "B.Fab")
		)
		(fp_line
			(start 0.12065 0.3048)
			(end 0.67945 0.3048)
			(stroke
				(width 0.1)
				(type default)
			)
			(layer "B.Fab")
		)
		(fp_line
			(start 0.67945 -0.305054)
			(end 0.12065 -0.305054)
			(stroke
				(width 0.1)
				(type default)
			)
			(layer "B.Fab")
		)
		(fp_line
			(start 0.67945 0.3048)
			(end 0.67945 -0.305054)
			(stroke
				(width 0.1)
				(type default)
			)
			(layer "B.Fab")
		)
		(pad "1" smd circle
			(at 0.40005 0 180)
			(size 0 0)
			(layers "B.Cu" "B.Mask" "B.Paste")
			(net "P3V3_E1S_0")
		)
		(pad "2" smd circle
			(at -0.40005 0 180)
			(size 0 0)
			(layers "B.Cu" "B.Mask" "B.Paste")
			(net "GND")
		)
	)
)
